# BASEBOARD_FAB2 (Tioga Pass) — schematic netlist excerpt (pin names and nets, part order shuffled) for the footprints in the layout excerpt that follows; sources: Cadence DE-HDL packaged netlist, KiCad conversion of Wiwynn_Tioga_Pass_MB.brd

R7F13  RES  20.0K 1% CHIP  pkg 0402  page 231 : A = VSENSE_PVPP_ABC ; B = VR_FB_PVPP_ABC
C22W12  SC22U16V5MX-4-GP  20%  pkg SMD-BCG5  page 240 : \1\ = VR_FET_SW_P12V_STBY_P3V3_STBY ; \2\ = GND
R1E6  RES  0.0 5% CHIP  pkg 0402  page 209 : A = VSENSE_PVCCIN_CPU1_P ; B = VSENSE_PVCCIN_CPU1_SKT_VSEN

(kicad_pcb
	(version 20260206)
	(generator "pcbnew")
	(generator_version "10.0")
	(general
		(thickness 1.6)
		(legacy_teardrops no)
	)
	(paper "A4")
	(title_block
		(title "Wiwynn_Tioga_Pass_MB.brd")
		(comment 1 "Tioga Pass / footprints 194-196 of 4770")
	)
	(layers
		(0 "F.Cu" signal "TOP")
		(4 "In1.Cu" signal "L2GND")
		(6 "In2.Cu" signal "L3")
		(8 "In3.Cu" signal "L4GND")
		(10 "In4.Cu" signal "L5")
		(12 "In5.Cu" signal "L6GND")
		(14 "In6.Cu" signal "L7VCC")
		(16 "In7.Cu" signal "L8VCC")
		(18 "In8.Cu" signal "L9GND")
		(20 "In9.Cu" signal "L10")
		(22 "In10.Cu" signal "L11GND")
		(24 "In11.Cu" signal "L12")
		(26 "In12.Cu" signal "L13GND")
		(2 "B.Cu" signal "BOTTOM")
		(9 "F.Adhes" user "F.Adhesive")
		(11 "B.Adhes" user "B.Adhesive")
		(13 "F.Paste" user "Package Geometry/Pastemask Top")
		(15 "B.Paste" user "Package Geometry/Pastemask Bottom")
		(5 "F.SilkS" user "Ref Des/Silkscreen Top")
		(7 "B.SilkS" user "Ref Des/Silkscreen Bottom")
		(1 "F.Mask" user "Board Geometry/Soldermask Top")
		(3 "B.Mask" user "Board Geometry/Soldermask Bottom")
		(17 "Dwgs.User" user "User.Drawings")
		(19 "Cmts.User" user "User.Comments")
		(21 "Eco1.User" user "User.Eco1")
		(23 "Eco2.User" user "User.Eco2")
		(25 "Edge.Cuts" user "Board Geometry/Outline")
		(27 "Margin" user)
		(31 "F.CrtYd" user "Package Geometry/Place Bound Top")
		(29 "B.CrtYd" user "Package Geometry/Place Bound Bottom")
		(35 "F.Fab" user "Ref Des/Assembly Top")
		(33 "B.Fab" user "Ref Des/Assembly Bottom")
	)
	(footprint ""
		(layer "F.Cu")
		(at 39.6748 -50.5714 90)
		(property "Reference" "R1E6"
			(at 0 0 90)
			(layer "F.SilkS")
			(hide yes)
			(effects
				(font
					(size 1.27 1.27)
				)
			)
		)
		(property "Value" ""
			(at 0 0 90)
			(layer "F.Fab")
			(effects
				(font
					(size 1.27 1.27)
				)
			)
		)
		(duplicate_pad_numbers_are_jumpers no)
		(fp_poly
			(pts
				(xy -0.2794 -0.1016) (xy 0.2794 -0.1016) (xy 0.2794 0.9906) (xy -0.2794 0.9906)
			)
			(stroke
				(width 0)
				(type default)
			)
			(fill no)
			(layer "F.CrtYd")
		)
		(fp_line
			(start 0.2794 -0.1016)
			(end -0.2794 -0.1016)
			(stroke
				(width 0.1)
				(type default)
			)
			(layer "F.Fab")
		)
		(fp_line
			(start -0.2794 -0.1016)
			(end -0.2794 0.9906)
			(stroke
				(width 0.1)
				(type default)
			)
			(layer "F.Fab")
		)
		(fp_line
			(start 0.2794 0.9906)
			(end 0.2794 -0.1016)
			(stroke
				(width 0.1)
				(type default)
			)
			(layer "F.Fab")
		)
		(fp_line
			(start -0.2794 0.9906)
			(end 0.2794 0.9906)
			(stroke
				(width 0.1)
				(type default)
			)
			(layer "F.Fab")
		)
		(pad "1" smd rect
			(at 0 0 90)
			(size 0.508 0.508)
			(layers "F.Cu" "F.Mask" "F.Paste")
			(net "VSENSE_PVCCIN_CPU1_P")
		)
		(pad "2" smd rect
			(at 0 0.889 90)
			(size 0.508 0.508)
			(layers "F.Cu" "F.Mask" "F.Paste")
			(net "VSENSE_PVCCIN_CPU1_SKT_VSEN")
		)
		(zone
			(layer "F.Cu")
			(hatch none 0.5)
			(connect_pads
				(clearance 0)
			)
			(min_thickness 0.25)
			(keepout
				(tracks allowed)
				(vias not_allowed)
				(pads allowed)
				(copperpour not_allowed)
				(footprints allowed)
			)
			(placement
				(enabled no)
				(sheetname "")
			)
			(fill
				(thermal_gap 0.5)
				(thermal_bridge_width 0.5)
				(island_removal_mode 0)
			)
			(polygon
				(pts
					(xy 39.9288 -50.3174) (xy 39.9288 -50.8254) (xy 40.3098 -50.8254) (xy 40.3098 -50.3174)
				)
			)
		)
		(zone
			(layer "F.Cu")
			(hatch none 0.5)
			(connect_pads
				(clearance 0)
			)
			(min_thickness 0.25)
			(keepout
				(tracks not_allowed)
				(vias allowed)
				(pads allowed)
				(copperpour not_allowed)
				(footprints allowed)
			)
			(placement
				(enabled no)
				(sheetname "")
			)
			(fill
				(thermal_gap 0.5)
				(thermal_bridge_width 0.5)
				(island_removal_mode 0)
			)
			(polygon
				(pts
					(xy 40.3098 -50.3174) (xy 40.3098 -50.8254) (xy 39.9288 -50.8254) (xy 39.9288 -50.3174)
				)
			)
		)
	)
	(footprint ""
		(layer "F.Cu")
		(at 335.788 -24.13 90)
		(property "Reference" "R7F13"
			(at 0 0 90)
			(layer "F.SilkS")
			(hide yes)
			(effects
				(font
					(size 1.27 1.27)
				)
			)
		)
		(property "Value" ""
			(at 0 0 90)
			(layer "F.Fab")
			(effects
				(font
					(size 1.27 1.27)
				)
			)
		)
		(duplicate_pad_numbers_are_jumpers no)
		(fp_rect
			(start -0.2794 -0.1016)
			(end 0.2794 0.9906)
			(stroke
				(width 0)
				(type default)
			)
			(fill no)
			(layer "F.CrtYd")
		)
		(fp_line
			(start 0.2794 -0.1016)
			(end -0.2794 -0.1016)
			(stroke
				(width 0.1)
				(type default)
			)
			(layer "F.Fab")
		)
		(fp_line
			(start -0.2794 -0.1016)
			(end -0.2794 0.9906)
			(stroke
				(width 0.1)
				(type default)
			)
			(layer "F.Fab")
		)
		(fp_line
			(start 0.2794 0.9906)
			(end 0.2794 -0.1016)
			(stroke
				(width 0.1)
				(type default)
			)
			(layer "F.Fab")
		)
		(fp_line
			(start -0.2794 0.9906)
			(end 0.2794 0.9906)
			(stroke
				(width 0.1)
				(type default)
			)
			(layer "F.Fab")
		)
		(pad "1" smd rect
			(at 0 0 90)
			(size 0.508 0.508)
			(layers "F.Cu" "F.Mask" "F.Paste")
			(net "VSENSE_PVPP_ABC")
		)
		(pad "2" smd rect
			(at 0 0.889 90)
			(size 0.508 0.508)
			(layers "F.Cu" "F.Mask" "F.Paste")
			(net "VR_FB_PVPP_ABC")
		)
		(zone
			(layer "F.Cu")
			(hatch none 0.5)
			(connect_pads
				(clearance 0)
			)
			(min_thickness 0.25)
			(keepout
				(tracks allowed)
				(vias not_allowed)
				(pads allowed)
				(copperpour not_allowed)
				(footprints allowed)
			)
			(placement
				(enabled no)
				(sheetname "")
			)
			(fill
				(thermal_gap 0.5)
				(thermal_bridge_width 0.5)
				(island_removal_mode 0)
			)
			(polygon
				(pts
					(xy 336.042 -23.876) (xy 336.423 -23.876) (xy 336.423 -24.384) (xy 336.042 -24.384)
				)
			)
		)
		(zone
			(layer "F.Cu")
			(hatch none 0.5)
			(connect_pads
				(clearance 0)
			)
			(min_thickness 0.25)
			(keepout
				(tracks not_allowed)
				(vias allowed)
				(pads allowed)
				(copperpour not_allowed)
				(footprints allowed)
			)
			(placement
				(enabled no)
				(sheetname "")
			)
			(fill
				(thermal_gap 0.5)
				(thermal_bridge_width 0.5)
				(island_removal_mode 0)
			)
			(polygon
				(pts
					(xy 336.042 -23.876) (xy 336.423 -23.876) (xy 336.423 -24.384) (xy 336.042 -24.384)
				)
			)
		)
	)
	(footprint ""
		(layer "F.Cu")
		(at 481.8126 -21.1582)
		(property "Reference" "C22W12"
			(at 0 0 0)
			(layer "F.SilkS")
			(hide yes)
			(effects
				(font
					(size 1.27 1.27)
				)
			)
		)
		(property "Value" "*"
			(at -0.0762 -6.2357 0)
			(unlocked yes)
			(layer "F.Fab")
			(hide yes)
			(effects
				(font
					(size 1.27 1.016)
					(thickness 0.1524)
				)
			)
		)
		(property "Device Type" "SC22U16V5MX-4-GP_SMD-BCG5-SC22A"
			(at -0.0762 -8.2677 0)
			(unlocked yes)
			(layer "F.Fab")
			(hide yes)
			(effects
				(font
					(size 1.27 1.016)
					(thickness 0.1524)
				)
			)
		)
		(duplicate_pad_numbers_are_jumpers no)
		(fp_line
			(start 0.635 0)
			(end -0.635 0)
			(stroke
				(width 0.508)
				(type default)
			)
			(layer "F.SilkS")
		)
		(fp_rect
			(start -0.9652 1.778)
			(end 0.9652 -1.778)
			(stroke
				(width 0)
				(type default)
			)
			(fill no)
			(layer "F.CrtYd")
		)
		(fp_poly
			(pts
				(xy -0.9652 -1.778) (xy 0.9652 -1.778) (xy 0.9652 1.778) (xy -0.9652 1.778)
			)
			(stroke
				(width 0)
				(type default)
			)
			(fill no)
			(layer "F.Fab")
		)
		(pad "1" smd rect
			(at 0 -0.9652)
			(size 1.397 1.143)
			(layers "F.Cu" "F.Mask" "F.Paste")
			(net "VR_FET_SW_P12V_STBY_P3V3_STBY")
		)
		(pad "2" smd rect
			(at 0 0.9652)
			(size 1.397 1.143)
			(layers "F.Cu" "F.Mask" "F.Paste")
			(net "GND")
		)
	)
)
